# S9S_MB_2U (Grand Teton) — schematic netlist excerpt (pin names and nets, part order shuffled) for the footprints in the layout excerpt that follows; sources: Cadence DE-HDL packaged netlist, KiCad conversion of 03242023_DA0F0TMBIJ0_F0T_Motherboard_J_brd_V01_OCP.brd

R4486  Q_RES  49.9 1% EMPTY  pkg 0402LF  page 196 : A = USB2_HOST_PCH_0_DP ; B = GND
PC1275  Q_CAP  0.22UF 25V 10% X7R  pkg C0402  page 282 : A = SW_PVNN_MAIN_CPU0_BST_R ; B = SW_PVNN_MAIN_CPU0_SW

(kicad_pcb
	(version 20260206)
	(generator "pcbnew")
	(generator_version "10.0")
	(general
		(thickness 1.6)
		(legacy_teardrops no)
	)
	(paper "A4")
	(title_block
		(title "03242023_DA0F0TMBIJ0_F0T_Motherboard_J_brd_V01_OCP.brd")
		(comment 1 "Grand Teton / footprints 1458-1459 of 6105")
	)
	(layers
		(0 "F.Cu" signal "TOP")
		(4 "In1.Cu" signal "GND")
		(6 "In2.Cu" signal "IN1")
		(8 "In3.Cu" signal "GND1")
		(10 "In4.Cu" signal "IN2")
		(12 "In5.Cu" signal "GND2")
		(14 "In6.Cu" signal "IN3")
		(16 "In7.Cu" signal "GND3")
		(18 "In8.Cu" signal "VCC")
		(20 "In9.Cu" signal "VCC1")
		(22 "In10.Cu" signal "GND4")
		(24 "In11.Cu" signal "IN4")
		(26 "In12.Cu" signal "GND5")
		(28 "In13.Cu" signal "IN5")
		(30 "In14.Cu" signal "GND6")
		(32 "In15.Cu" signal "IN6")
		(34 "In16.Cu" signal "GND7")
		(2 "B.Cu" signal "BOTTOM")
		(9 "F.Adhes" user "F.Adhesive")
		(11 "B.Adhes" user "B.Adhesive")
		(13 "F.Paste" user "Package Geometry/Pastemask Top")
		(15 "B.Paste" user "Package Geometry/Pastemask Bottom")
		(5 "F.SilkS" user "Ref Des/Silkscreen Top")
		(7 "B.SilkS" user "Ref Des/Silkscreen Bottom")
		(1 "F.Mask" user "Board Geometry/Soldermask Top")
		(3 "B.Mask" user "Board Geometry/Soldermask Bottom")
		(17 "Dwgs.User" user "User.Drawings")
		(19 "Cmts.User" user "User.Comments")
		(21 "Eco1.User" user "User.Eco1")
		(23 "Eco2.User" user "User.Eco2")
		(25 "Edge.Cuts" user "Board Geometry/Outline")
		(27 "Margin" user)
		(31 "F.CrtYd" user "Package Geometry/Place Bound Top")
		(29 "B.CrtYd" user "Package Geometry/Place Bound Bottom")
		(35 "F.Fab" user "Ref Des/Assembly Top")
		(33 "B.Fab" user "Ref Des/Assembly Bottom")
	)
	(footprint ""
		(layer "F.Cu")
		(at 435.431692 -181.13121 90)
		(property "Reference" "PC1275"
			(at 0 0 90)
			(layer "F.SilkS")
			(hide yes)
			(effects
				(font
					(size 1.27 1.27)
				)
			)
		)
		(property "Value" ""
			(at 0 0 90)
			(layer "F.Fab")
			(effects
				(font
					(size 1.27 1.27)
				)
			)
		)
		(duplicate_pad_numbers_are_jumpers no)
		(fp_line
			(start 0.7874 -0.4064)
			(end 0.7874 0.4064)
			(stroke
				(width 0.1524)
				(type default)
			)
			(layer "F.SilkS")
		)
		(fp_line
			(start -0.7874 -0.4064)
			(end 0.7874 -0.4064)
			(stroke
				(width 0.1524)
				(type default)
			)
			(layer "F.SilkS")
		)
		(fp_line
			(start 0.7874 0.4064)
			(end -0.7874 0.4064)
			(stroke
				(width 0.1524)
				(type default)
			)
			(layer "F.SilkS")
		)
		(fp_line
			(start -0.7874 0.4064)
			(end -0.7874 -0.4064)
			(stroke
				(width 0.1524)
				(type default)
			)
			(layer "F.SilkS")
		)
		(fp_line
			(start -0.12065 -0.305054)
			(end -0.12065 -0.2794)
			(stroke
				(width 0.1)
				(type default)
			)
			(layer "F.Fab")
		)
		(fp_line
			(start -0.67945 -0.305054)
			(end -0.12065 -0.305054)
			(stroke
				(width 0.1)
				(type default)
			)
			(layer "F.Fab")
		)
		(fp_line
			(start 0.67945 -0.3048)
			(end 0.67945 0.3048)
			(stroke
				(width 0.1)
				(type default)
			)
			(layer "F.Fab")
		)
		(fp_line
			(start 0.12065 -0.3048)
			(end 0.67945 -0.3048)
			(stroke
				(width 0.1)
				(type default)
			)
			(layer "F.Fab")
		)
		(fp_line
			(start 0.12065 -0.2794)
			(end 0.12065 -0.3048)
			(stroke
				(width 0.1)
				(type default)
			)
			(layer "F.Fab")
		)
		(fp_line
			(start -0.12065 -0.2794)
			(end 0.12065 -0.2794)
			(stroke
				(width 0.1)
				(type default)
			)
			(layer "F.Fab")
		)
		(fp_line
			(start 0.120396 0.2794)
			(end -0.12065 0.2794)
			(stroke
				(width 0.1)
				(type default)
			)
			(layer "F.Fab")
		)
		(fp_line
			(start -0.12065 0.2794)
			(end -0.12065 0.3048)
			(stroke
				(width 0.1)
				(type default)
			)
			(layer "F.Fab")
		)
		(fp_line
			(start 0.67945 0.3048)
			(end 0.120396 0.3048)
			(stroke
				(width 0.1)
				(type default)
			)
			(layer "F.Fab")
		)
		(fp_line
			(start 0.120396 0.3048)
			(end 0.120396 0.2794)
			(stroke
				(width 0.1)
				(type default)
			)
			(layer "F.Fab")
		)
		(fp_line
			(start -0.12065 0.3048)
			(end -0.67945 0.3048)
			(stroke
				(width 0.1)
				(type default)
			)
			(layer "F.Fab")
		)
		(fp_line
			(start -0.67945 0.3048)
			(end -0.67945 -0.305054)
			(stroke
				(width 0.1)
				(type default)
			)
			(layer "F.Fab")
		)
		(pad "1" smd circle
			(at -0.40005 0 90)
			(size 0 0)
			(layers "F.Cu" "F.Mask" "F.Paste")
			(net "SW_PVNN_MAIN_CPU0_BST_R")
		)
		(pad "2" smd circle
			(at 0.40005 0 90)
			(size 0 0)
			(layers "F.Cu" "F.Mask" "F.Paste")
			(net "SW_PVNN_MAIN_CPU0_SW")
		)
	)
	(footprint ""
		(layer "F.Cu")
		(at 155.27909 -46.751748 180)
		(property "Reference" "R4486"
			(at 0 0 180)
			(layer "F.SilkS")
			(hide yes)
			(effects
				(font
					(size 1.27 1.27)
				)
			)
		)
		(property "Value" ""
			(at 0 0 180)
			(layer "F.Fab")
			(effects
				(font
					(size 1.27 1.27)
				)
			)
		)
		(duplicate_pad_numbers_are_jumpers no)
		(fp_line
			(start 0.7874 0.4064)
			(end -0.08763 0.4064)
			(stroke
				(width 0.1524)
				(type default)
			)
			(layer "F.SilkS")
		)
		(fp_line
			(start 0.7874 -0.4064)
			(end 0.7874 0.4064)
			(stroke
				(width 0.1524)
				(type default)
			)
			(layer "F.SilkS")
		)
		(fp_line
			(start 0.05715 -0.4064)
			(end 0.7874 -0.4064)
			(stroke
				(width 0.1524)
				(type default)
			)
			(layer "F.SilkS")
		)
		(fp_line
			(start 0.67945 0.3048)
			(end 0.120396 0.3048)
			(stroke
				(width 0.1)
				(type default)
			)
			(layer "F.Fab")
		)
		(fp_line
			(start 0.67945 -0.3048)
			(end 0.67945 0.3048)
			(stroke
				(width 0.1)
				(type default)
			)
			(layer "F.Fab")
		)
		(fp_line
			(start 0.12065 -0.2794)
			(end 0.12065 -0.3048)
			(stroke
				(width 0.1)
				(type default)
			)
			(layer "F.Fab")
		)
		(fp_line
			(start 0.12065 -0.3048)
			(end 0.67945 -0.3048)
			(stroke
				(width 0.1)
				(type default)
			)
			(layer "F.Fab")
		)
		(fp_line
			(start 0.120396 0.3048)
			(end 0.120396 0.2794)
			(stroke
				(width 0.1)
				(type default)
			)
			(layer "F.Fab")
		)
		(fp_line
			(start 0.120396 0.2794)
			(end -0.12065 0.2794)
			(stroke
				(width 0.1)
				(type default)
			)
			(layer "F.Fab")
		)
		(fp_line
			(start -0.12065 0.3048)
			(end -0.67945 0.3048)
			(stroke
				(width 0.1)
				(type default)
			)
			(layer "F.Fab")
		)
		(fp_line
			(start -0.12065 0.2794)
			(end -0.12065 0.3048)
			(stroke
				(width 0.1)
				(type default)
			)
			(layer "F.Fab")
		)
		(fp_line
			(start -0.12065 -0.2794)
			(end 0.12065 -0.2794)
			(stroke
				(width 0.1)
				(type default)
			)
			(layer "F.Fab")
		)
		(fp_line
			(start -0.12065 -0.305054)
			(end -0.12065 -0.2794)
			(stroke
				(width 0.1)
				(type default)
			)
			(layer "F.Fab")
		)
		(fp_line
			(start -0.67945 0.3048)
			(end -0.67945 -0.305054)
			(stroke
				(width 0.1)
				(type default)
			)
			(layer "F.Fab")
		)
		(fp_line
			(start -0.67945 -0.305054)
			(end -0.12065 -0.305054)
			(stroke
				(width 0.1)
				(type default)
			)
			(layer "F.Fab")
		)
		(pad "1" smd circle
			(at -0.40005 0 180)
			(size 0 0)
			(layers "F.Cu" "F.Mask" "F.Paste")
			(net "USB2_HOST_PCH_0_DP")
		)
		(pad "2" smd circle
			(at 0.40005 0 180)
			(size 0 0)
			(layers "F.Cu" "F.Mask" "F.Paste")
			(net "GND")
		)
	)
)
